(kicad_pcb
	(version 20260206)
	(generator "pcbnew")
	(generator_version "10.0")
	(general
		(thickness 1.6)
		(legacy_teardrops no)
	)
	(paper "A4")
	(title_block
		(title "Bryce Canyon_F.DPB_16315-1-OCP.brd")
		(comment 1 "Bryce Canyon / footprints 953-958 of 2223")
	)
	(layers
		(0 "F.Cu" signal "TOP")
		(4 "In1.Cu" signal "L2GND")
		(6 "In2.Cu" signal "L3")
		(8 "In3.Cu" signal "L4GND")
		(10 "In4.Cu" signal "L5")
		(12 "In5.Cu" signal "L6VCC")
		(14 "In6.Cu" signal "L7VCC")
		(16 "In7.Cu" signal "L8")
		(18 "In8.Cu" signal "L9GND")
		(20 "In9.Cu" signal "L10")
		(22 "In10.Cu" signal "L11GND")
		(2 "B.Cu" signal "BOTTOM")
		(9 "F.Adhes" user "F.Adhesive")
		(11 "B.Adhes" user "B.Adhesive")
		(13 "F.Paste" user "Package Geometry/Pastemask Top")
		(15 "B.Paste" user "Package Geometry/Pastemask Bottom")
		(5 "F.SilkS" user "Ref Des/Silkscreen Top")
		(7 "B.SilkS" user "Ref Des/Silkscreen Bottom")
		(1 "F.Mask" user "Board Geometry/Soldermask Top")
		(3 "B.Mask" user "Board Geometry/Soldermask Bottom")
		(17 "Dwgs.User" user "User.Drawings")
		(19 "Cmts.User" user "User.Comments")
		(21 "Eco1.User" user "User.Eco1")
		(23 "Eco2.User" user "User.Eco2")
		(25 "Edge.Cuts" user "Board Geometry/Outline")
		(27 "Margin" user)
		(31 "F.CrtYd" user "Package Geometry/Place Bound Top")
		(29 "B.CrtYd" user "Package Geometry/Place Bound Bottom")
		(35 "F.Fab" user "Ref Des/Assembly Top")
		(33 "B.Fab" user "Ref Des/Assembly Bottom")
	)
	(footprint ""
		(layer "F.Cu")
		(at 233.903266 -261.722362)
		(property "Reference" "R38"
			(at 0 0 0)
			(layer "F.SilkS")
			(hide yes)
			(effects
				(font
					(size 1.27 1.27)
				)
			)
		)
		(property "Value" "4K7R2F-GP"
			(at 0.064008 -3.993896 0)
			(unlocked yes)
			(layer "F.Fab")
			(hide yes)
			(effects
				(font
					(size 1.016 1.016)
					(thickness 0.1524)
				)
			)
		)
		(property "Device Type" "R402H16"
			(at 0.064008 -5.517896 0)
			(unlocked yes)
			(layer "F.Fab")
			(hide yes)
			(effects
				(font
					(size 1.016 1.016)
					(thickness 0.1524)
				)
			)
		)
		(duplicate_pad_numbers_are_jumpers no)
		(fp_line
			(start -0.508 -0.9398)
			(end -0.508 0.9398)
			(stroke
				(width 0.1524)
				(type default)
			)
			(layer "F.SilkS")
		)
		(fp_line
			(start 0.508 -0.9398)
			(end -0.508 -0.9398)
			(stroke
				(width 0.1524)
				(type default)
			)
			(layer "F.SilkS")
		)
		(fp_rect
			(start -0.508 0.9398)
			(end 0.508 -0.9398)
			(stroke
				(width 0)
				(type default)
			)
			(fill no)
			(layer "F.CrtYd")
		)
		(fp_rect
			(start -0.508 0.9398)
			(end 0.508 -0.9398)
			(stroke
				(width 0)
				(type default)
			)
			(fill no)
			(layer "F.Fab")
		)
		(pad "1" smd custom
			(at 0 -0.4445)
			(size 0.1397 0.1397)
			(layers "F.Cu" "F.Mask" "F.Paste")
			(net "P3V3_STBY_A")
			(options
				(clearance outline)
				(anchor circle)
			)
			(primitives
				(gr_poly
					(pts
						(arc
							(start -0.1778 -0.2794)
							(mid -0.249642 -0.249642)
							(end -0.2794 -0.1778)
						)
						(arc
							(start -0.2794 0.1778)
							(mid -0.249642 0.249642)
							(end -0.1778 0.2794)
						)
						(arc
							(start 0.1778 0.2794)
							(mid 0.249642 0.249642)
							(end 0.2794 0.1778)
						)
						(arc
							(start 0.2794 -0.1778)
							(mid 0.249642 -0.249642)
							(end 0.1778 -0.2794)
						)
					)
					(width 0)
					(fill yes)
				)
			)
		)
		(pad "2" smd custom
			(at 0 0.4445)
			(size 0.1397 0.1397)
			(layers "F.Cu" "F.Mask" "F.Paste")
			(net "IO_EXP4_A2")
			(options
				(clearance outline)
				(anchor circle)
			)
			(primitives
				(gr_poly
					(pts
						(arc
							(start -0.1778 -0.2794)
							(mid -0.249642 -0.249642)
							(end -0.2794 -0.1778)
						)
						(arc
							(start -0.2794 0.1778)
							(mid -0.249642 0.249642)
							(end -0.1778 0.2794)
						)
						(arc
							(start 0.1778 0.2794)
							(mid 0.249642 0.249642)
							(end 0.2794 0.1778)
						)
						(arc
							(start 0.2794 -0.1778)
							(mid 0.249642 -0.249642)
							(end 0.1778 -0.2794)
						)
					)
					(width 0)
					(fill yes)
				)
			)
		)
	)
	(footprint ""
		(layer "F.Cu")
		(at 3.849878 -120.499886)
		(property "Reference" ""
			(at 0 0 0)
			(layer "F.SilkS")
			(hide yes)
			(effects
				(font
					(size 1.27 1.27)
				)
			)
		)
		(property "Value" "*"
			(at -4.9911 1.5494 0)
			(unlocked yes)
			(layer "F.Fab")
			(hide yes)
			(effects
				(font
					(size 1.016 1.016)
					(thickness 0.1524)
				)
			)
		)
		(duplicate_pad_numbers_are_jumpers no)
		(fp_poly
			(pts
				(arc
					(start 4.064 0)
					(mid -4.064 0)
					(end 4.064 0)
				)
			)
			(stroke
				(width 0)
				(type default)
			)
			(fill no)
			(layer "B.CrtYd")
		)
		(fp_poly
			(pts
				(arc
					(start 4.064 0)
					(mid -4.064 0)
					(end 4.064 0)
				)
			)
			(stroke
				(width 0)
				(type default)
			)
			(fill no)
			(layer "F.CrtYd")
		)
		(fp_poly
			(pts
				(arc
					(start 4.064 0)
					(mid -4.064 0)
					(end 4.064 0)
				)
			)
			(stroke
				(width 0)
				(type default)
			)
			(fill no)
			(layer "B.Fab")
		)
		(fp_poly
			(pts
				(arc
					(start 4.064 0)
					(mid -4.064 0)
					(end 4.064 0)
				)
			)
			(stroke
				(width 0)
				(type default)
			)
			(fill no)
			(layer "F.Fab")
		)
		(pad "1" thru_hole circle
			(at 0 0)
			(size 7.5184 7.5184)
			(drill oval 6.223 4.2164)
			(layers "*.Cu" "*.Mask")
			(remove_unused_layers no)
			(net "Net_58")
			(clearance -1.143)
			(thermal_gap 0.1524)
			(padstack
				(mode front_inner_back)
				(layer "Inner"
					(shape oval)
					(size 4.9276 6.9342)
					(clearance 0.1524)
				)
				(layer "B.Cu"
					(shape circle)
					(size 7.5184 7.5184)
					(clearance -1.143)
				)
			)
		)
		(zone
			(layers "F.Cu" "B.Cu" "In1.Cu" "In2.Cu" "In3.Cu" "In4.Cu" "In5.Cu" "In6.Cu"
				"In7.Cu" "In8.Cu" "In9.Cu" "In10.Cu"
			)
			(hatch none 0.5)
			(connect_pads
				(clearance 0)
			)
			(min_thickness 0.25)
			(keepout
				(tracks not_allowed)
				(vias allowed)
				(pads allowed)
				(copperpour not_allowed)
				(footprints allowed)
			)
			(placement
				(enabled no)
				(sheetname "")
			)
			(fill
				(thermal_gap 0.5)
				(thermal_bridge_width 0.5)
				(island_removal_mode 0)
			)
			(polygon
				(pts
					(arc
						(start 7.609078 -120.499886)
						(mid 0.090678 -120.499886)
						(end 7.609078 -120.499886)
					)
				)
			)
		)
	)
	(footprint ""
		(layer "F.Cu")
		(at 263.233662 -342.897968 90)
		(property "Reference" "R980"
			(at 0 0 90)
			(layer "F.SilkS")
			(hide yes)
			(effects
				(font
					(size 1.27 1.27)
				)
			)
		)
		(property "Value" "0R2J-2-GP"
			(at 0.064008 -3.993896 90)
			(unlocked yes)
			(layer "F.Fab")
			(hide yes)
			(effects
				(font
					(size 1.016 1.016)
					(thickness 0.1524)
				)
			)
		)
		(property "Device Type" "R402H16"
			(at 0.064008 -5.517896 90)
			(unlocked yes)
			(layer "F.Fab")
			(hide yes)
			(effects
				(font
					(size 1.016 1.016)
					(thickness 0.1524)
				)
			)
		)
		(duplicate_pad_numbers_are_jumpers no)
		(fp_line
			(start 0.508 -0.9398)
			(end -0.508 -0.9398)
			(stroke
				(width 0.1524)
				(type default)
			)
			(layer "F.SilkS")
		)
		(fp_line
			(start -0.508 -0.9398)
			(end -0.508 0.9398)
			(stroke
				(width 0.1524)
				(type default)
			)
			(layer "F.SilkS")
		)
		(fp_rect
			(start -0.508 0.9398)
			(end 0.508 -0.9398)
			(stroke
				(width 0)
				(type default)
			)
			(fill no)
			(layer "F.CrtYd")
		)
		(fp_rect
			(start -0.508 0.9398)
			(end 0.508 -0.9398)
			(stroke
				(width 0)
				(type default)
			)
			(fill no)
			(layer "F.Fab")
		)
		(pad "1" smd custom
			(at 0 -0.4445 90)
			(size 0.1397 0.1397)
			(layers "F.Cu" "F.Mask" "F.Paste")
			(net "GND")
			(options
				(clearance outline)
				(anchor circle)
			)
			(primitives
				(gr_poly
					(pts
						(arc
							(start -0.1778 -0.2794)
							(mid -0.249642 -0.249642)
							(end -0.2794 -0.1778)
						)
						(arc
							(start -0.2794 0.1778)
							(mid -0.249642 0.249642)
							(end -0.1778 0.2794)
						)
						(arc
							(start 0.1778 0.2794)
							(mid 0.249642 0.249642)
							(end 0.2794 0.1778)
						)
						(arc
							(start 0.2794 -0.1778)
							(mid 0.249642 -0.249642)
							(end 0.1778 -0.2794)
						)
					)
					(width 0)
					(fill yes)
				)
			)
		)
		(pad "2" smd custom
			(at 0 0.4445 90)
			(size 0.1397 0.1397)
			(layers "F.Cu" "F.Mask" "F.Paste")
			(net "SCC_A_SLOT_ID_0")
			(options
				(clearance outline)
				(anchor circle)
			)
			(primitives
				(gr_poly
					(pts
						(arc
							(start -0.1778 -0.2794)
							(mid -0.249642 -0.249642)
							(end -0.2794 -0.1778)
						)
						(arc
							(start -0.2794 0.1778)
							(mid -0.249642 0.249642)
							(end -0.1778 0.2794)
						)
						(arc
							(start 0.1778 0.2794)
							(mid 0.249642 0.249642)
							(end 0.2794 0.1778)
						)
						(arc
							(start 0.2794 -0.1778)
							(mid 0.249642 -0.249642)
							(end 0.1778 -0.2794)
						)
					)
					(width 0)
					(fill yes)
				)
			)
		)
	)
	(footprint ""
		(layer "F.Cu")
		(at 263.53897 -380.367794)
		(property "Reference" "Q227"
			(at 0 0 0)
			(layer "F.SilkS")
			(hide yes)
			(effects
				(font
					(size 1.27 1.27)
				)
			)
		)
		(property "Value" "IRFH8201TRPBF-GP"
			(at -4.2164 -4.3688 0)
			(unlocked yes)
			(layer "F.Fab")
			(hide yes)
			(effects
				(font
					(size 1.016 1.016)
					(thickness 0.1524)
				)
			)
		)
		(property "Device Type" "PPAK-5PH42"
			(at -4.2164 -5.8928 0)
			(unlocked yes)
			(layer "F.Fab")
			(hide yes)
			(effects
				(font
					(size 1.016 1.016)
					(thickness 0.1524)
				)
			)
		)
		(duplicate_pad_numbers_are_jumpers no)
		(fp_line
			(start -3.0353 4.9276)
			(end -3.0353 3.9624)
			(stroke
				(width 0.3302)
				(type default)
			)
			(layer "F.SilkS")
		)
		(fp_line
			(start -2.8956 -2.794)
			(end 2.8956 -2.794)
			(stroke
				(width 0.1524)
				(type default)
			)
			(layer "F.SilkS")
		)
		(fp_line
			(start -2.8956 4.826)
			(end -2.8956 -2.794)
			(stroke
				(width 0.1524)
				(type default)
			)
			(layer "F.SilkS")
		)
		(fp_line
			(start -1.9431 4.9276)
			(end -3.0353 4.9276)
			(stroke
				(width 0.3302)
				(type default)
			)
			(layer "F.SilkS")
		)
		(fp_line
			(start 2.8956 -2.794)
			(end 2.8956 4.826)
			(stroke
				(width 0.1524)
				(type default)
			)
			(layer "F.SilkS")
		)
		(fp_line
			(start 2.8956 4.826)
			(end -2.8956 4.826)
			(stroke
				(width 0.1524)
				(type default)
			)
			(layer "F.SilkS")
		)
		(fp_poly
			(pts
				(xy -2.3622 5.334) (xy -1.4986 5.334) (xy -1.9304 4.9022)
			)
			(stroke
				(width 0)
				(type default)
			)
			(fill yes)
			(layer "F.SilkS")
		)
		(fp_poly
			(pts
				(xy -2.6416 -0.3556) (xy -0.3556 -0.3556) (xy -0.3556 -2.54) (xy -2.6416 -2.54)
			)
			(stroke
				(width 0)
				(type default)
			)
			(fill yes)
			(layer "F.Paste")
		)
		(fp_poly
			(pts
				(xy -2.6416 2.54) (xy -0.3556 2.54) (xy -0.3556 0.3556) (xy -2.6416 0.3556)
			)
			(stroke
				(width 0)
				(type default)
			)
			(fill yes)
			(layer "F.Paste")
		)
		(fp_poly
			(pts
				(xy 0.3556 -0.3556) (xy 2.6416 -0.3556) (xy 2.6416 -2.54) (xy 0.3556 -2.54)
			)
			(stroke
				(width 0)
				(type default)
			)
			(fill yes)
			(layer "F.Paste")
		)
		(fp_poly
			(pts
				(xy 0.3556 2.54) (xy 2.6416 2.54) (xy 2.6416 0.3556) (xy 0.3556 0.3556)
			)
			(stroke
				(width 0)
				(type default)
			)
			(fill yes)
			(layer "F.Paste")
		)
		(fp_rect
			(start -2.5781 3.9878)
			(end 2.5781 -2.1082)
			(stroke
				(width 0)
				(type default)
			)
			(fill no)
			(layer "F.CrtYd")
		)
		(fp_poly
			(pts
				(xy -3.1496 5.08) (xy -3.1496 -3.048) (xy 3.1496 -3.048) (xy 3.1496 3.9751) (xy 2.5781 3.9751) (xy 2.5781 -2.1082)
				(xy -2.5781 -2.1082) (xy -2.5781 3.9878) (xy 3.1496 3.9878) (xy 3.1496 5.08)
			)
			(stroke
				(width 0)
				(type default)
			)
			(fill no)
			(layer "F.CrtYd")
		)
		(fp_rect
			(start -3.1496 5.08)
			(end 3.1496 -3.048)
			(stroke
				(width 0)
				(type default)
			)
			(fill no)
			(layer "F.Fab")
		)
		(pad "1" smd rect
			(at -1.905 3.81)
			(size 0.762 1.524)
			(layers "F.Cu" "F.Mask" "F.Paste")
			(net "P12V_A")
		)
		(pad "2" smd rect
			(at -0.635 3.81)
			(size 0.762 1.524)
			(layers "F.Cu" "F.Mask" "F.Paste")
			(net "P12V_A")
		)
		(pad "3" smd rect
			(at 0.635 3.81)
			(size 0.762 1.524)
			(layers "F.Cu" "F.Mask" "F.Paste")
			(net "P12V_A")
		)
		(pad "4" smd rect
			(at 1.905 3.81)
			(size 0.762 1.524)
			(layers "F.Cu" "F.Mask" "F.Paste")
			(net "MB3_12V_CTRL_GATE2")
		)
		(pad "5" smd rect
			(at 0 0)
			(size 5.2832 5.08)
			(layers "F.Cu" "F.Mask" "F.Paste")
			(net "MB3_P12V_IN_R")
		)
		(pad "6" smd rect
			(at 0.635 -2.032)
			(size 0.0254 0.0254)
			(layers "F.Cu" "F.Mask" "F.Paste")
			(net "MB3_P12V_IN_R")
		)
		(pad "7" smd rect
			(at -0.635 -2.032)
			(size 0.0254 0.0254)
			(layers "F.Cu" "F.Mask" "F.Paste")
			(net "MB3_P12V_IN_R")
		)
		(pad "8" smd rect
			(at -1.905 -2.032)
			(size 0.0254 0.0254)
			(layers "F.Cu" "F.Mask" "F.Paste")
			(net "MB3_P12V_IN_R")
		)
	)
	(footprint ""
		(layer "F.Cu")
		(at 245.364 -231.14)
		(property "Reference" "R81"
			(at 0 0 0)
			(layer "F.SilkS")
			(hide yes)
			(effects
				(font
					(size 1.27 1.27)
				)
			)
		)
		(property "Value" "4K7R2F-GP"
			(at 0.064008 -3.993896 0)
			(unlocked yes)
			(layer "F.Fab")
			(hide yes)
			(effects
				(font
					(size 1.016 1.016)
					(thickness 0.1524)
				)
			)
		)
		(property "Device Type" "R402H16"
			(at 0.064008 -5.517896 0)
			(unlocked yes)
			(layer "F.Fab")
			(hide yes)
			(effects
				(font
					(size 1.016 1.016)
					(thickness 0.1524)
				)
			)
		)
		(duplicate_pad_numbers_are_jumpers no)
		(fp_line
			(start -0.508 -0.9398)
			(end -0.508 0.9398)
			(stroke
				(width 0.1524)
				(type default)
			)
			(layer "F.SilkS")
		)
		(fp_line
			(start 0.508 -0.9398)
			(end -0.508 -0.9398)
			(stroke
				(width 0.1524)
				(type default)
			)
			(layer "F.SilkS")
		)
		(fp_rect
			(start -0.508 0.9398)
			(end 0.508 -0.9398)
			(stroke
				(width 0)
				(type default)
			)
			(fill no)
			(layer "F.CrtYd")
		)
		(fp_rect
			(start -0.508 0.9398)
			(end 0.508 -0.9398)
			(stroke
				(width 0)
				(type default)
			)
			(fill no)
			(layer "F.Fab")
		)
		(pad "1" smd custom
			(at 0 -0.4445)
			(size 0.1397 0.1397)
			(layers "F.Cu" "F.Mask" "F.Paste")
			(net "IO_EXP2_A2")
			(options
				(clearance outline)
				(anchor circle)
			)
			(primitives
				(gr_poly
					(pts
						(arc
							(start -0.1778 -0.2794)
							(mid -0.249642 -0.249642)
							(end -0.2794 -0.1778)
						)
						(arc
							(start -0.2794 0.1778)
							(mid -0.249642 0.249642)
							(end -0.1778 0.2794)
						)
						(arc
							(start 0.1778 0.2794)
							(mid 0.249642 0.249642)
							(end 0.2794 0.1778)
						)
						(arc
							(start 0.2794 -0.1778)
							(mid 0.249642 -0.249642)
							(end 0.1778 -0.2794)
						)
					)
					(width 0)
					(fill yes)
				)
			)
		)
		(pad "2" smd custom
			(at 0 0.4445)
			(size 0.1397 0.1397)
			(layers "F.Cu" "F.Mask" "F.Paste")
			(net "GND")
			(options
				(clearance outline)
				(anchor circle)
			)
			(primitives
				(gr_poly
					(pts
						(arc
							(start -0.1778 -0.2794)
							(mid -0.249642 -0.249642)
							(end -0.2794 -0.1778)
						)
						(arc
							(start -0.2794 0.1778)
							(mid -0.249642 0.249642)
							(end -0.1778 0.2794)
						)
						(arc
							(start 0.1778 0.2794)
							(mid 0.249642 0.249642)
							(end 0.2794 0.1778)
						)
						(arc
							(start 0.2794 -0.1778)
							(mid 0.249642 -0.249642)
							(end 0.1778 -0.2794)
						)
					)
					(width 0)
					(fill yes)
				)
			)
		)
	)
	(footprint ""
		(layer "F.Cu")
		(at 113.581942 -272.726404 180)
		(property "Reference" "R207"
			(at 0 0 180)
			(layer "F.SilkS")
			(hide yes)
			(effects
				(font
					(size 1.27 1.27)
				)
			)
		)
		(property "Value" "1KR2F-3-GP"
			(at 0.064008 -3.993896 180)
			(unlocked yes)
			(layer "F.Fab")
			(hide yes)
			(effects
				(font
					(size 1.016 1.016)
					(thickness 0.1524)
				)
			)
		)
		(property "Device Type" "R402H16"
			(at 0.064008 -5.517896 180)
			(unlocked yes)
			(layer "F.Fab")
			(hide yes)
			(effects
				(font
					(size 1.016 1.016)
					(thickness 0.1524)
				)
			)
		)
		(duplicate_pad_numbers_are_jumpers no)
		(fp_line
			(start 0.508 -0.9398)
			(end -0.508 -0.9398)
			(stroke
				(width 0.1524)
				(type default)
			)
			(layer "F.SilkS")
		)
		(fp_line
			(start -0.508 -0.9398)
			(end -0.508 0.9398)
			(stroke
				(width 0.1524)
				(type default)
			)
			(layer "F.SilkS")
		)
		(fp_rect
			(start -0.508 0.9398)
			(end 0.508 -0.9398)
			(stroke
				(width 0)
				(type default)
			)
			(fill no)
			(layer "F.CrtYd")
		)
		(fp_rect
			(start -0.508 0.9398)
			(end 0.508 -0.9398)
			(stroke
				(width 0)
				(type default)
			)
			(fill no)
			(layer "F.Fab")
		)
		(pad "1" smd custom
			(at 0 -0.4445 180)
			(size 0.1397 0.1397)
			(layers "F.Cu" "F.Mask" "F.Paste")
			(net "P3V3_STBY_A")
			(options
				(clearance outline)
				(anchor circle)
			)
			(primitives
				(gr_poly
					(pts
						(arc
							(start -0.1778 -0.2794)
							(mid -0.249642 -0.249642)
							(end -0.2794 -0.1778)
						)
						(arc
							(start -0.2794 0.1778)
							(mid -0.249642 0.249642)
							(end -0.1778 0.2794)
						)
						(arc
							(start 0.1778 0.2794)
							(mid 0.249642 0.249642)
							(end 0.2794 0.1778)
						)
						(arc
							(start 0.2794 -0.1778)
							(mid 0.249642 -0.249642)
							(end 0.1778 -0.2794)
						)
					)
					(width 0)
					(fill yes)
				)
			)
		)
		(pad "2" smd custom
			(at 0 0.4445 180)
			(size 0.1397 0.1397)
			(layers "F.Cu" "F.Mask" "F.Paste")
			(net "SW_PWR_R_HDD3")
			(options
				(clearance outline)
				(anchor circle)
			)
			(primitives
				(gr_poly
					(pts
						(arc
							(start -0.1778 -0.2794)
							(mid -0.249642 -0.249642)
							(end -0.2794 -0.1778)
						)
						(arc
							(start -0.2794 0.1778)
							(mid -0.249642 0.249642)
							(end -0.1778 0.2794)
						)
						(arc
							(start 0.1778 0.2794)
							(mid 0.249642 0.249642)
							(end 0.2794 0.1778)
						)
						(arc
							(start 0.2794 -0.1778)
							(mid 0.249642 -0.249642)
							(end 0.1778 -0.2794)
						)
					)
					(width 0)
					(fill yes)
				)
			)
		)
	)
)
